# BASEBOARD_FAB2 (Tioga Pass) — schematic netlist excerpt (pin names and nets, part order shuffled) for the footprints in the layout excerpt that follows; sources: Cadence DE-HDL packaged netlist, KiCad conversion of Wiwynn_Tioga_Pass_MB.brd

J9B1  CONN9_H51826001  CONN  pkg PIP2  page 176
  VBUS  = P5V_USB
  DN  = USB2_P01_ESD_DN
  DP  = USB2_P01_ESD_DP
  GND  = GND
  STDA_SSRXN  = SMB_DEBUG_STBY_LVC3_SCL_CONN
  STDA_SSRXP  = SMB_DEBUG_STBY_LVC3_SDA_CONN
  GND_DRAIN  = DEBUG_CARD2_PRSNT
  STDA_SSTXN  = SPA_MID_DBG2_TX
  STDA_SSTXP  = SPA_MID_DBG2_RX
  MH1  = GND
  MH2  = GND
  MH3  = GND
  MH4  = GND

(kicad_pcb
	(version 20260206)
	(generator "pcbnew")
	(generator_version "10.0")
	(general
		(thickness 1.6)
		(legacy_teardrops no)
	)
	(paper "A4")
	(title_block
		(title "Wiwynn_Tioga_Pass_MB.brd")
		(comment 1 "Tioga Pass / footprint 1483 of 4770 (J9B1), pads 1-13 of 13")
	)
	(layers
		(0 "F.Cu" signal "TOP")
		(4 "In1.Cu" signal "L2GND")
		(6 "In2.Cu" signal "L3")
		(8 "In3.Cu" signal "L4GND")
		(10 "In4.Cu" signal "L5")
		(12 "In5.Cu" signal "L6GND")
		(14 "In6.Cu" signal "L7VCC")
		(16 "In7.Cu" signal "L8VCC")
		(18 "In8.Cu" signal "L9GND")
		(20 "In9.Cu" signal "L10")
		(22 "In10.Cu" signal "L11GND")
		(24 "In11.Cu" signal "L12")
		(26 "In12.Cu" signal "L13GND")
		(2 "B.Cu" signal "BOTTOM")
		(9 "F.Adhes" user "F.Adhesive")
		(11 "B.Adhes" user "B.Adhesive")
		(13 "F.Paste" user "Package Geometry/Pastemask Top")
		(15 "B.Paste" user "Package Geometry/Pastemask Bottom")
		(5 "F.SilkS" user "Ref Des/Silkscreen Top")
		(7 "B.SilkS" user "Ref Des/Silkscreen Bottom")
		(1 "F.Mask" user "Board Geometry/Soldermask Top")
		(3 "B.Mask" user "Board Geometry/Soldermask Bottom")
		(17 "Dwgs.User" user "User.Drawings")
		(19 "Cmts.User" user "User.Comments")
		(21 "Eco1.User" user "User.Eco1")
		(23 "Eco2.User" user "User.Eco2")
		(25 "Edge.Cuts" user "Board Geometry/Outline")
		(27 "Margin" user)
		(31 "F.CrtYd" user "Package Geometry/Place Bound Top")
		(29 "B.CrtYd" user "Package Geometry/Place Bound Bottom")
		(35 "F.Fab" user "Ref Des/Assembly Top")
		(33 "B.Fab" user "Ref Des/Assembly Bottom")
	)
	(footprint ""
		(layer "F.Cu")
		(at 481.251006 -131.655312 90)
		(property "Reference" "J9B1"
			(at -2.522728 5.79501 0)
			(unlocked yes)
			(layer "B.SilkS")
			(effects
				(font
					(size 0.7874 0.5842)
					(thickness 0.1524)
				)
				(justify left mirror)
			)
		)
		(property "Value" ""
			(at 0 0 90)
			(layer "F.Fab")
			(effects
				(font
					(size 1.27 1.27)
				)
			)
		)
		(duplicate_pad_numbers_are_jumpers no)
		(pad "1" thru_hole rect
			(at 0 0 90)
			(size 1.143 1.143)
			(drill 0.762)
			(layers "*.Cu" "*.Mask")
			(remove_unused_layers no)
			(net "P5V_USB")
			(clearance 0.127)
			(thermal_gap 0.127)
			(padstack
				(mode front_inner_back)
				(layer "Inner"
					(shape circle)
					(size 1.143 1.143)
					(clearance 0.127)
				)
				(layer "B.Cu"
					(shape rect)
					(size 1.143 1.143)
					(clearance 0.127)
				)
			)
		)
		(pad "2" thru_hole circle
			(at 0 2.500122 90)
			(size 1.143 1.143)
			(drill 0.762)
			(layers "*.Cu" "*.Mask")
			(remove_unused_layers no)
			(net "USB2_P01_ESD_DN")
			(clearance 0.127)
			(thermal_gap 0.127)
		)
		(pad "3" thru_hole circle
			(at 0 4.500118 90)
			(size 1.143 1.143)
			(drill 0.762)
			(layers "*.Cu" "*.Mask")
			(remove_unused_layers no)
			(net "USB2_P01_ESD_DP")
			(clearance 0.127)
			(thermal_gap 0.127)
		)
		(pad "4" thru_hole circle
			(at 0 6.999986 90)
			(size 1.143 1.143)
			(drill 0.762)
			(layers "*.Cu" "*.Mask")
			(remove_unused_layers no)
			(net "GND")
			(clearance 0.127)
			(thermal_gap 0.127)
		)
		(pad "5" thru_hole circle
			(at 1.800098 7.500112 90)
			(size 1.143 1.143)
			(drill 0.762)
			(layers "*.Cu" "*.Mask")
			(remove_unused_layers no)
			(net "SMB_DEBUG_STBY_LVC3_SCL_CONN")
			(clearance 0.127)
			(thermal_gap 0.127)
		)
		(pad "6" thru_hole circle
			(at 1.800098 5.500116 90)
			(size 1.143 1.143)
			(drill 0.762)
			(layers "*.Cu" "*.Mask")
			(remove_unused_layers no)
			(net "SMB_DEBUG_STBY_LVC3_SDA_CONN")
			(clearance 0.127)
			(thermal_gap 0.127)
		)
		(pad "7" thru_hole circle
			(at 1.800098 3.50012 90)
			(size 1.143 1.143)
			(drill 0.762)
			(layers "*.Cu" "*.Mask")
			(remove_unused_layers no)
			(net "DEBUG_CARD2_PRSNT")
			(clearance 0.127)
			(thermal_gap 0.127)
		)
		(pad "8" thru_hole circle
			(at 1.800098 1.500124 90)
			(size 1.143 1.143)
			(drill 0.762)
			(layers "*.Cu" "*.Mask")
			(remove_unused_layers no)
			(net "SPA_MID_DBG2_TX")
			(clearance 0.127)
			(thermal_gap 0.127)
		)
		(pad "9" thru_hole circle
			(at 1.800098 -0.500126 90)
			(size 1.143 1.143)
			(drill 0.762)
			(layers "*.Cu" "*.Mask")
			(remove_unused_layers no)
			(net "SPA_MID_DBG2_RX")
			(clearance 0.127)
			(thermal_gap 0.127)
		)
		(pad "MH1" thru_hole oval
			(at -1.810004 -1.869948 90)
			(size 1.1684 1.778)
			(drill oval 0.7874 1.397)
			(layers "*.Cu" "*.Mask")
			(remove_unused_layers no)
			(net "GND")
			(clearance 0.127)
			(thermal_gap 0.127)
		)
		(pad "MH2" thru_hole oval
			(at -1.810004 8.830056 90)
			(size 1.1684 2.4892)
			(drill oval 0.7874 2.1082)
			(layers "*.Cu" "*.Mask")
			(remove_unused_layers no)
			(net "GND")
			(clearance 0.127)
			(thermal_gap 0.127)
		)
		(pad "MH3" thru_hole oval
			(at 3.610102 8.830056 90)
			(size 1.1684 1.778)
			(drill oval 0.7874 1.397)
			(layers "*.Cu" "*.Mask")
			(remove_unused_layers no)
			(net "GND")
			(clearance 0.127)
			(thermal_gap 0.127)
		)
		(pad "MH4" thru_hole oval
			(at 3.610102 -1.869948 90)
			(size 1.1684 2.4892)
			(drill oval 0.7874 2.1082)
			(layers "*.Cu" "*.Mask")
			(remove_unused_layers no)
			(net "GND")
			(clearance 0.127)
			(thermal_gap 0.127)
		)
	)
)
